# T6G (Grand Teton) — schematic netlist excerpt (pin names and nets, part order shuffled) for the footprints in the layout excerpt that follows; sources: Cadence DE-HDL packaged netlist, KiCad conversion of 04192023_DAF0TMB3IC0_F0TG_MB_C_brd_V02_OCP.brd

C802  Q_CAP  100UF 4V 20% X6S  pkg C0805  page 301 : A = P0V9_CPU0_RT2_2A ; B = GND
C3909  Q_CAP  22UF 4V 20% X6S  pkg C0402  page 72 : A = PVDD18_S5_P1 ; B = GND
C2629  Q_CAP  22UF 4V 20% X6S  pkg C0402  page 70 : A = PVDD11_S3_P0 ; B = GND

(kicad_pcb
	(version 20260206)
	(generator "pcbnew")
	(generator_version "10.0")
	(general
		(thickness 1.6)
		(legacy_teardrops no)
	)
	(paper "A4")
	(title_block
		(title "04192023_DAF0TMB3IC0_F0TG_MB_C_brd_V02_OCP.brd")
		(comment 1 "Grand Teton / footprints 7100-7102 of 8354")
	)
	(layers
		(0 "F.Cu" signal "TOP")
		(4 "In1.Cu" signal "GND")
		(6 "In2.Cu" signal "IN1")
		(8 "In3.Cu" signal "GND1")
		(10 "In4.Cu" signal "IN2")
		(12 "In5.Cu" signal "GND2")
		(14 "In6.Cu" signal "IN3")
		(16 "In7.Cu" signal "GND3")
		(18 "In8.Cu" signal "VCC")
		(20 "In9.Cu" signal "VCC1")
		(22 "In10.Cu" signal "GND4")
		(24 "In11.Cu" signal "IN4")
		(26 "In12.Cu" signal "GND5")
		(28 "In13.Cu" signal "IN5")
		(30 "In14.Cu" signal "GND6")
		(32 "In15.Cu" signal "IN6")
		(34 "In16.Cu" signal "GND7")
		(2 "B.Cu" signal "BOTTOM")
		(9 "F.Adhes" user "F.Adhesive")
		(11 "B.Adhes" user "B.Adhesive")
		(13 "F.Paste" user "Package Geometry/Pastemask Top")
		(15 "B.Paste" user "Package Geometry/Pastemask Bottom")
		(5 "F.SilkS" user "Ref Des/Silkscreen Top")
		(7 "B.SilkS" user "Ref Des/Silkscreen Bottom")
		(1 "F.Mask" user "Board Geometry/Soldermask Top")
		(3 "B.Mask" user "Board Geometry/Soldermask Bottom")
		(17 "Dwgs.User" user "User.Drawings")
		(19 "Cmts.User" user "User.Comments")
		(21 "Eco1.User" user "User.Eco1")
		(23 "Eco2.User" user "User.Eco2")
		(25 "Edge.Cuts" user "Board Geometry/Outline")
		(27 "Margin" user)
		(31 "F.CrtYd" user "Package Geometry/Place Bound Top")
		(29 "B.CrtYd" user "Package Geometry/Place Bound Bottom")
		(35 "F.Fab" user "Ref Des/Assembly Top")
		(33 "B.Fab" user "Ref Des/Assembly Bottom")
	)
	(footprint ""
		(layer "B.Cu")
		(at 105.960164 -255.555242 180)
		(property "Reference" "C3909"
			(at 0 0 0)
			(layer "B.SilkS")
			(hide yes)
			(effects
				(font
					(size 1.27 1.27)
				)
				(justify mirror)
			)
		)
		(property "Value" ""
			(at 0 0 0)
			(layer "B.Fab")
			(effects
				(font
					(size 1.27 1.27)
				)
				(justify mirror)
			)
		)
		(duplicate_pad_numbers_are_jumpers no)
		(fp_line
			(start 0.7874 0.4064)
			(end 0.7874 -0.4064)
			(stroke
				(width 0.1524)
				(type default)
			)
			(layer "B.SilkS")
		)
		(fp_line
			(start 0.7874 -0.4064)
			(end -0.7874 -0.4064)
			(stroke
				(width 0.1524)
				(type default)
			)
			(layer "B.SilkS")
		)
		(fp_line
			(start -0.7874 0.4064)
			(end 0.7874 0.4064)
			(stroke
				(width 0.1524)
				(type default)
			)
			(layer "B.SilkS")
		)
		(fp_line
			(start -0.7874 -0.4064)
			(end -0.7874 0.4064)
			(stroke
				(width 0.1524)
				(type default)
			)
			(layer "B.SilkS")
		)
		(fp_line
			(start 0.67945 0.3048)
			(end 0.67945 -0.305054)
			(stroke
				(width 0.1)
				(type default)
			)
			(layer "B.Fab")
		)
		(fp_line
			(start 0.67945 -0.305054)
			(end 0.12065 -0.305054)
			(stroke
				(width 0.1)
				(type default)
			)
			(layer "B.Fab")
		)
		(fp_line
			(start 0.12065 0.3048)
			(end 0.67945 0.3048)
			(stroke
				(width 0.1)
				(type default)
			)
			(layer "B.Fab")
		)
		(fp_line
			(start 0.12065 0.2794)
			(end 0.12065 0.3048)
			(stroke
				(width 0.1)
				(type default)
			)
			(layer "B.Fab")
		)
		(fp_line
			(start 0.12065 -0.2794)
			(end -0.12065 -0.2794)
			(stroke
				(width 0.1)
				(type default)
			)
			(layer "B.Fab")
		)
		(fp_line
			(start 0.12065 -0.305054)
			(end 0.12065 -0.2794)
			(stroke
				(width 0.1)
				(type default)
			)
			(layer "B.Fab")
		)
		(fp_line
			(start -0.120396 0.3048)
			(end -0.120396 0.2794)
			(stroke
				(width 0.1)
				(type default)
			)
			(layer "B.Fab")
		)
		(fp_line
			(start -0.120396 0.2794)
			(end 0.12065 0.2794)
			(stroke
				(width 0.1)
				(type default)
			)
			(layer "B.Fab")
		)
		(fp_line
			(start -0.12065 -0.2794)
			(end -0.12065 -0.3048)
			(stroke
				(width 0.1)
				(type default)
			)
			(layer "B.Fab")
		)
		(fp_line
			(start -0.12065 -0.3048)
			(end -0.67945 -0.3048)
			(stroke
				(width 0.1)
				(type default)
			)
			(layer "B.Fab")
		)
		(fp_line
			(start -0.67945 0.3048)
			(end -0.120396 0.3048)
			(stroke
				(width 0.1)
				(type default)
			)
			(layer "B.Fab")
		)
		(fp_line
			(start -0.67945 -0.3048)
			(end -0.67945 0.3048)
			(stroke
				(width 0.1)
				(type default)
			)
			(layer "B.Fab")
		)
		(pad "1" smd circle
			(at 0.40005 0)
			(size 0 0)
			(layers "B.Cu" "B.Mask" "B.Paste")
			(net "PVDD18_S5_P1")
		)
		(pad "2" smd circle
			(at -0.40005 0)
			(size 0 0)
			(layers "B.Cu" "B.Mask" "B.Paste")
			(net "GND")
		)
	)
	(footprint ""
		(layer "B.Cu")
		(at 350.723454 -266.00531)
		(property "Reference" "C2629"
			(at 0 0 0)
			(layer "B.SilkS")
			(hide yes)
			(effects
				(font
					(size 1.27 1.27)
				)
				(justify mirror)
			)
		)
		(property "Value" ""
			(at 0 0 0)
			(layer "B.Fab")
			(effects
				(font
					(size 1.27 1.27)
				)
				(justify mirror)
			)
		)
		(duplicate_pad_numbers_are_jumpers no)
		(fp_line
			(start -0.7874 -0.4064)
			(end -0.7874 0.4064)
			(stroke
				(width 0.1524)
				(type default)
			)
			(layer "B.SilkS")
		)
		(fp_line
			(start -0.7874 0.4064)
			(end 0.7874 0.4064)
			(stroke
				(width 0.1524)
				(type default)
			)
			(layer "B.SilkS")
		)
		(fp_line
			(start 0.7874 -0.4064)
			(end -0.7874 -0.4064)
			(stroke
				(width 0.1524)
				(type default)
			)
			(layer "B.SilkS")
		)
		(fp_line
			(start 0.7874 0.4064)
			(end 0.7874 -0.4064)
			(stroke
				(width 0.1524)
				(type default)
			)
			(layer "B.SilkS")
		)
		(fp_line
			(start -0.67945 -0.3048)
			(end -0.67945 0.3048)
			(stroke
				(width 0.1)
				(type default)
			)
			(layer "B.Fab")
		)
		(fp_line
			(start -0.67945 0.3048)
			(end -0.120396 0.3048)
			(stroke
				(width 0.1)
				(type default)
			)
			(layer "B.Fab")
		)
		(fp_line
			(start -0.12065 -0.3048)
			(end -0.67945 -0.3048)
			(stroke
				(width 0.1)
				(type default)
			)
			(layer "B.Fab")
		)
		(fp_line
			(start -0.12065 -0.2794)
			(end -0.12065 -0.3048)
			(stroke
				(width 0.1)
				(type default)
			)
			(layer "B.Fab")
		)
		(fp_line
			(start -0.120396 0.2794)
			(end 0.12065 0.2794)
			(stroke
				(width 0.1)
				(type default)
			)
			(layer "B.Fab")
		)
		(fp_line
			(start -0.120396 0.3048)
			(end -0.120396 0.2794)
			(stroke
				(width 0.1)
				(type default)
			)
			(layer "B.Fab")
		)
		(fp_line
			(start 0.12065 -0.305054)
			(end 0.12065 -0.2794)
			(stroke
				(width 0.1)
				(type default)
			)
			(layer "B.Fab")
		)
		(fp_line
			(start 0.12065 -0.2794)
			(end -0.12065 -0.2794)
			(stroke
				(width 0.1)
				(type default)
			)
			(layer "B.Fab")
		)
		(fp_line
			(start 0.12065 0.2794)
			(end 0.12065 0.3048)
			(stroke
				(width 0.1)
				(type default)
			)
			(layer "B.Fab")
		)
		(fp_line
			(start 0.12065 0.3048)
			(end 0.67945 0.3048)
			(stroke
				(width 0.1)
				(type default)
			)
			(layer "B.Fab")
		)
		(fp_line
			(start 0.67945 -0.305054)
			(end 0.12065 -0.305054)
			(stroke
				(width 0.1)
				(type default)
			)
			(layer "B.Fab")
		)
		(fp_line
			(start 0.67945 0.3048)
			(end 0.67945 -0.305054)
			(stroke
				(width 0.1)
				(type default)
			)
			(layer "B.Fab")
		)
		(pad "1" smd circle
			(at 0.40005 0 180)
			(size 0 0)
			(layers "B.Cu" "B.Mask" "B.Paste")
			(net "PVDD11_S3_P0")
		)
		(pad "2" smd circle
			(at -0.40005 0 180)
			(size 0 0)
			(layers "B.Cu" "B.Mask" "B.Paste")
			(net "GND")
		)
	)
	(footprint ""
		(layer "B.Cu")
		(at 398.040606 -397.228568)
		(property "Reference" "C802"
			(at 0 0 0)
			(layer "B.SilkS")
			(hide yes)
			(effects
				(font
					(size 1.27 1.27)
				)
				(justify mirror)
			)
		)
		(property "Value" ""
			(at 0 0 0)
			(layer "B.Fab")
			(effects
				(font
					(size 1.27 1.27)
				)
				(justify mirror)
			)
		)
		(duplicate_pad_numbers_are_jumpers no)
		(fp_line
			(start -1.524 -0.762)
			(end -1.524 0.762)
			(stroke
				(width 0.1524)
				(type default)
			)
			(layer "B.SilkS")
		)
		(fp_line
			(start -1.524 0.762)
			(end 1.524 0.762)
			(stroke
				(width 0.1524)
				(type default)
			)
			(layer "B.SilkS")
		)
		(fp_line
			(start 1.524 -0.762)
			(end -1.524 -0.762)
			(stroke
				(width 0.1524)
				(type default)
			)
			(layer "B.SilkS")
		)
		(fp_line
			(start 1.524 0.762)
			(end 1.524 -0.762)
			(stroke
				(width 0.1524)
				(type default)
			)
			(layer "B.SilkS")
		)
		(fp_line
			(start -1.1049 -0.724916)
			(end 1.1049 -0.724916)
			(stroke
				(width 0.1)
				(type default)
			)
			(layer "B.Fab")
		)
		(fp_line
			(start -1.1049 0.724916)
			(end -1.1049 -0.724916)
			(stroke
				(width 0.1)
				(type default)
			)
			(layer "B.Fab")
		)
		(fp_line
			(start 1.1049 -0.724916)
			(end 1.1049 0.724916)
			(stroke
				(width 0.1)
				(type default)
			)
			(layer "B.Fab")
		)
		(fp_line
			(start 1.1049 0.724916)
			(end -1.1049 0.724916)
			(stroke
				(width 0.1)
				(type default)
			)
			(layer "B.Fab")
		)
		(pad "1" smd rect
			(at 0.889 0)
			(size 1.016 1.27)
			(layers "B.Cu" "B.Mask" "B.Paste")
			(net "P0V9_CPU0_RT2_2A")
		)
		(pad "2" smd rect
			(at -0.889 0)
			(size 1.016 1.27)
			(layers "B.Cu" "B.Mask" "B.Paste")
			(net "GND")
		)
	)
)
